(kicad_pcb
	(version 20260206)
	(generator "pcbnew")
	(generator_version "10.0")
	(general
		(thickness 1.6)
		(legacy_teardrops no)
	)
	(paper "A4")
	(title_block
		(title "01162023_DA0F0TEBIF0_F0T_Expander_BD_F_brd_V02_OCP.brd")
		(comment 1 "Grand Teton / footprints 9309-9318 of 9728")
	)
	(layers
		(0 "F.Cu" signal "TOP")
		(4 "In1.Cu" signal "GND")
		(6 "In2.Cu" signal "VCC")
		(8 "In3.Cu" signal "VCC1")
		(10 "In4.Cu" signal "GND1")
		(12 "In5.Cu" signal "IN1")
		(14 "In6.Cu" signal "GND2")
		(16 "In7.Cu" signal "IN2")
		(18 "In8.Cu" signal "GND3")
		(20 "In9.Cu" signal "IN3")
		(22 "In10.Cu" signal "GND4")
		(24 "In11.Cu" signal "IN4")
		(26 "In12.Cu" signal "GND5")
		(28 "In13.Cu" signal "IN5")
		(30 "In14.Cu" signal "GND6")
		(32 "In15.Cu" signal "IN6")
		(34 "In16.Cu" signal "GND7")
		(2 "B.Cu" signal "BOTTOM")
		(9 "F.Adhes" user "F.Adhesive")
		(11 "B.Adhes" user "B.Adhesive")
		(13 "F.Paste" user "Package Geometry/Pastemask Top")
		(15 "B.Paste" user "Package Geometry/Pastemask Bottom")
		(5 "F.SilkS" user "Ref Des/Silkscreen Top")
		(7 "B.SilkS" user "Ref Des/Silkscreen Bottom")
		(1 "F.Mask" user "Board Geometry/Soldermask Top")
		(3 "B.Mask" user "Board Geometry/Soldermask Bottom")
		(17 "Dwgs.User" user "User.Drawings")
		(19 "Cmts.User" user "User.Comments")
		(21 "Eco1.User" user "User.Eco1")
		(23 "Eco2.User" user "User.Eco2")
		(25 "Edge.Cuts" user "Board Geometry/Outline")
		(27 "Margin" user)
		(31 "F.CrtYd" user "Package Geometry/Place Bound Top")
		(29 "B.CrtYd" user "Package Geometry/Place Bound Bottom")
		(35 "F.Fab" user "Ref Des/Assembly Top")
		(33 "B.Fab" user "Ref Des/Assembly Bottom")
	)
	(footprint ""
		(layer "B.Cu")
		(at 402.67001 -305.399948 -90)
		(property "Reference" "C3499"
			(at 0 0 90)
			(layer "B.SilkS")
			(hide yes)
			(effects
				(font
					(size 1.27 1.27)
				)
				(justify mirror)
			)
		)
		(property "Value" ""
			(at 0 0 90)
			(layer "B.Fab")
			(effects
				(font
					(size 1.27 1.27)
				)
				(justify mirror)
			)
		)
		(duplicate_pad_numbers_are_jumpers no)
		(fp_line
			(start -0.299974 0.150114)
			(end 0.299974 0.150114)
			(stroke
				(width 0.1)
				(type default)
			)
			(layer "B.Fab")
		)
		(fp_line
			(start 0.299974 0.150114)
			(end 0.299974 -0.150114)
			(stroke
				(width 0.1)
				(type default)
			)
			(layer "B.Fab")
		)
		(fp_line
			(start -0.299974 -0.150114)
			(end -0.299974 0.150114)
			(stroke
				(width 0.1)
				(type default)
			)
			(layer "B.Fab")
		)
		(fp_line
			(start 0.299974 -0.150114)
			(end -0.299974 -0.150114)
			(stroke
				(width 0.1)
				(type default)
			)
			(layer "B.Fab")
		)
		(pad "1" smd rect
			(at 0.2667 0 90)
			(size 0.3048 0.381)
			(layers "B.Cu" "B.Mask" "B.Paste")
			(net "P1V25_SERDES_VDDPLL_PEX3")
		)
		(pad "2" smd rect
			(at -0.2667 0 90)
			(size 0.3048 0.381)
			(layers "B.Cu" "B.Mask" "B.Paste")
			(net "GND")
		)
	)
	(footprint ""
		(layer "B.Cu")
		(at 286.149796 -288.299906 90)
		(property "Reference" "C3281"
			(at 0 0 90)
			(layer "B.SilkS")
			(hide yes)
			(effects
				(font
					(size 1.27 1.27)
				)
				(justify mirror)
			)
		)
		(property "Value" ""
			(at 0 0 90)
			(layer "B.Fab")
			(effects
				(font
					(size 1.27 1.27)
				)
				(justify mirror)
			)
		)
		(duplicate_pad_numbers_are_jumpers no)
		(fp_line
			(start 0.299974 -0.150114)
			(end -0.299974 -0.150114)
			(stroke
				(width 0.1)
				(type default)
			)
			(layer "B.Fab")
		)
		(fp_line
			(start -0.299974 -0.150114)
			(end -0.299974 0.150114)
			(stroke
				(width 0.1)
				(type default)
			)
			(layer "B.Fab")
		)
		(fp_line
			(start 0.299974 0.150114)
			(end 0.299974 -0.150114)
			(stroke
				(width 0.1)
				(type default)
			)
			(layer "B.Fab")
		)
		(fp_line
			(start -0.299974 0.150114)
			(end 0.299974 0.150114)
			(stroke
				(width 0.1)
				(type default)
			)
			(layer "B.Fab")
		)
		(pad "1" smd rect
			(at 0.2667 0 270)
			(size 0.3048 0.381)
			(layers "B.Cu" "B.Mask" "B.Paste")
			(net "P1V25_PEX2")
		)
		(pad "2" smd rect
			(at -0.2667 0 270)
			(size 0.3048 0.381)
			(layers "B.Cu" "B.Mask" "B.Paste")
			(net "GND")
		)
	)
	(footprint ""
		(layer "B.Cu")
		(at 240.467388 -220.514672 180)
		(property "Reference" "C3617"
			(at 0 0 0)
			(layer "B.SilkS")
			(hide yes)
			(effects
				(font
					(size 1.27 1.27)
				)
				(justify mirror)
			)
		)
		(property "Value" ""
			(at 0 0 0)
			(layer "B.Fab")
			(effects
				(font
					(size 1.27 1.27)
				)
				(justify mirror)
			)
		)
		(duplicate_pad_numbers_are_jumpers no)
		(fp_line
			(start 0.69215 0.2921)
			(end 0.69215 -0.2921)
			(stroke
				(width 0.1524)
				(type default)
			)
			(layer "B.SilkS")
		)
		(fp_line
			(start 0.69215 -0.2921)
			(end -0.69215 -0.2921)
			(stroke
				(width 0.1524)
				(type default)
			)
			(layer "B.SilkS")
		)
		(fp_line
			(start -0.69215 0.2921)
			(end 0.69215 0.2921)
			(stroke
				(width 0.1524)
				(type default)
			)
			(layer "B.SilkS")
		)
		(fp_line
			(start -0.69215 -0.2921)
			(end -0.69215 0.2921)
			(stroke
				(width 0.1524)
				(type default)
			)
			(layer "B.SilkS")
		)
		(fp_line
			(start 0.51435 0.2794)
			(end 0.51435 -0.2794)
			(stroke
				(width 0.1)
				(type default)
			)
			(layer "B.Fab")
		)
		(fp_line
			(start 0.51435 -0.2794)
			(end -0.51435 -0.2794)
			(stroke
				(width 0.1)
				(type default)
			)
			(layer "B.Fab")
		)
		(fp_line
			(start -0.51435 0.2794)
			(end 0.51435 0.2794)
			(stroke
				(width 0.1)
				(type default)
			)
			(layer "B.Fab")
		)
		(fp_line
			(start -0.51435 -0.2794)
			(end -0.51435 0.2794)
			(stroke
				(width 0.1)
				(type default)
			)
			(layer "B.Fab")
		)
		(pad "1" smd circle
			(at 0.40005 0)
			(size 0 0)
			(layers "B.Cu" "B.Mask" "B.Paste")
			(net "BIC_ADCVREFP1")
		)
		(pad "2" smd circle
			(at -0.40005 0)
			(size 0 0)
			(layers "B.Cu" "B.Mask" "B.Paste")
			(net "GND")
		)
		(zone
			(layer "B.Cu")
			(hatch none 0.5)
			(connect_pads
				(clearance 0)
			)
			(min_thickness 0.25)
			(keepout
				(tracks not_allowed)
				(vias allowed)
				(pads allowed)
				(copperpour not_allowed)
				(footprints allowed)
			)
			(placement
				(enabled no)
				(sheetname "")
			)
			(fill
				(thermal_gap 0.5)
				(thermal_bridge_width 0.5)
				(island_removal_mode 0)
			)
			(polygon
				(pts
					(xy 240.276888 -220.602302) (xy 240.368328 -220.660468) (xy 240.567718 -220.660468) (xy 240.657888 -220.602302)
					(xy 240.657888 -220.427042) (xy 240.567718 -220.368622) (xy 240.368328 -220.368622) (xy 240.276888 -220.426788)
				)
			)
		)
	)
	(footprint ""
		(layer "B.Cu")
		(at 355.803962 -325.310246 -90)
		(property "Reference" "C4369"
			(at 0 0 90)
			(layer "B.SilkS")
			(hide yes)
			(effects
				(font
					(size 1.27 1.27)
				)
				(justify mirror)
			)
		)
		(property "Value" ""
			(at 0 0 90)
			(layer "B.Fab")
			(effects
				(font
					(size 1.27 1.27)
				)
				(justify mirror)
			)
		)
		(duplicate_pad_numbers_are_jumpers no)
		(fp_line
			(start -1.2954 0.5842)
			(end 1.2954 0.5842)
			(stroke
				(width 0.1524)
				(type default)
			)
			(layer "B.SilkS")
		)
		(fp_line
			(start 1.2954 0.5842)
			(end 1.2954 -0.5842)
			(stroke
				(width 0.1524)
				(type default)
			)
			(layer "B.SilkS")
		)
		(fp_line
			(start -1.2954 -0.5842)
			(end -1.2954 0.5842)
			(stroke
				(width 0.1524)
				(type default)
			)
			(layer "B.SilkS")
		)
		(fp_line
			(start 1.2954 -0.5842)
			(end -1.2954 -0.5842)
			(stroke
				(width 0.1524)
				(type default)
			)
			(layer "B.SilkS")
		)
		(fp_line
			(start -0.8636 0.4572)
			(end 0.8636 0.4572)
			(stroke
				(width 0.1)
				(type default)
			)
			(layer "B.Fab")
		)
		(fp_line
			(start 0.8636 0.4572)
			(end 0.8636 0.4064)
			(stroke
				(width 0.1)
				(type default)
			)
			(layer "B.Fab")
		)
		(fp_line
			(start -1.1938 0.4064)
			(end -0.8636 0.4064)
			(stroke
				(width 0.1)
				(type default)
			)
			(layer "B.Fab")
		)
		(fp_line
			(start -0.8636 0.4064)
			(end -0.8636 0.4572)
			(stroke
				(width 0.1)
				(type default)
			)
			(layer "B.Fab")
		)
		(fp_line
			(start 0.8636 0.4064)
			(end 1.1938 0.4064)
			(stroke
				(width 0.1)
				(type default)
			)
			(layer "B.Fab")
		)
		(fp_line
			(start 1.1938 0.4064)
			(end 1.1938 -0.4064)
			(stroke
				(width 0.1)
				(type default)
			)
			(layer "B.Fab")
		)
		(fp_line
			(start -1.1938 -0.4064)
			(end -1.1938 0.4064)
			(stroke
				(width 0.1)
				(type default)
			)
			(layer "B.Fab")
		)
		(fp_line
			(start -0.8636 -0.4064)
			(end -1.1938 -0.4064)
			(stroke
				(width 0.1)
				(type default)
			)
			(layer "B.Fab")
		)
		(fp_line
			(start 0.8636 -0.4064)
			(end 0.8636 -0.4572)
			(stroke
				(width 0.1)
				(type default)
			)
			(layer "B.Fab")
		)
		(fp_line
			(start 1.1938 -0.4064)
			(end 0.8636 -0.4064)
			(stroke
				(width 0.1)
				(type default)
			)
			(layer "B.Fab")
		)
		(fp_line
			(start -0.8636 -0.4572)
			(end -0.8636 -0.4064)
			(stroke
				(width 0.1)
				(type default)
			)
			(layer "B.Fab")
		)
		(fp_line
			(start 0.8636 -0.4572)
			(end -0.8636 -0.4572)
			(stroke
				(width 0.1)
				(type default)
			)
			(layer "B.Fab")
		)
		(pad "1" smd rect
			(at 0.7366 0 180)
			(size 0.7112 0.8128)
			(layers "B.Cu" "B.Mask" "B.Paste")
			(net "P0V8_SERDES_VDDA_PEX3_C3")
		)
		(pad "2" smd rect
			(at -0.7366 0 180)
			(size 0.7112 0.8128)
			(layers "B.Cu" "B.Mask" "B.Paste")
			(net "GND")
		)
	)
	(footprint ""
		(layer "B.Cu")
		(at 121.077228 -281.024838 90)
		(property "Reference" "PC95"
			(at 0 0 90)
			(layer "B.SilkS")
			(hide yes)
			(effects
				(font
					(size 1.27 1.27)
				)
				(justify mirror)
			)
		)
		(property "Value" ""
			(at 0 0 90)
			(layer "B.Fab")
			(effects
				(font
					(size 1.27 1.27)
				)
				(justify mirror)
			)
		)
		(duplicate_pad_numbers_are_jumpers no)
		(fp_line
			(start 1.524 -0.762)
			(end -1.524 -0.762)
			(stroke
				(width 0.1524)
				(type default)
			)
			(layer "B.SilkS")
		)
		(fp_line
			(start -1.524 -0.762)
			(end -1.524 0.762)
			(stroke
				(width 0.1524)
				(type default)
			)
			(layer "B.SilkS")
		)
		(fp_line
			(start 1.524 0.762)
			(end 1.524 -0.762)
			(stroke
				(width 0.1524)
				(type default)
			)
			(layer "B.SilkS")
		)
		(fp_line
			(start -1.524 0.762)
			(end 1.524 0.762)
			(stroke
				(width 0.1524)
				(type default)
			)
			(layer "B.SilkS")
		)
		(fp_line
			(start 1.1049 -0.724916)
			(end 1.1049 0.724916)
			(stroke
				(width 0.1)
				(type default)
			)
			(layer "B.Fab")
		)
		(fp_line
			(start -1.1049 -0.724916)
			(end 1.1049 -0.724916)
			(stroke
				(width 0.1)
				(type default)
			)
			(layer "B.Fab")
		)
		(fp_line
			(start 1.1049 0.724916)
			(end -1.1049 0.724916)
			(stroke
				(width 0.1)
				(type default)
			)
			(layer "B.Fab")
		)
		(fp_line
			(start -1.1049 0.724916)
			(end -1.1049 -0.724916)
			(stroke
				(width 0.1)
				(type default)
			)
			(layer "B.Fab")
		)
		(pad "1" smd rect
			(at 0.889 0 90)
			(size 1.016 1.27)
			(layers "B.Cu" "B.Mask" "B.Paste")
			(net "SW_P12V_P0V8_PEX1_FLT")
		)
		(pad "2" smd rect
			(at -0.889 0 90)
			(size 1.016 1.27)
			(layers "B.Cu" "B.Mask" "B.Paste")
			(net "GND")
		)
	)
	(footprint ""
		(layer "B.Cu")
		(at 231.86771 -216.704164)
		(property "Reference" "C3608"
			(at 0 0 0)
			(layer "B.SilkS")
			(hide yes)
			(effects
				(font
					(size 1.27 1.27)
				)
				(justify mirror)
			)
		)
		(property "Value" ""
			(at 0 0 0)
			(layer "B.Fab")
			(effects
				(font
					(size 1.27 1.27)
				)
				(justify mirror)
			)
		)
		(duplicate_pad_numbers_are_jumpers no)
		(fp_line
			(start -0.69215 -0.2921)
			(end -0.69215 0.2921)
			(stroke
				(width 0.1524)
				(type default)
			)
			(layer "B.SilkS")
		)
		(fp_line
			(start -0.69215 0.2921)
			(end 0.69215 0.2921)
			(stroke
				(width 0.1524)
				(type default)
			)
			(layer "B.SilkS")
		)
		(fp_line
			(start 0.69215 -0.2921)
			(end -0.69215 -0.2921)
			(stroke
				(width 0.1524)
				(type default)
			)
			(layer "B.SilkS")
		)
		(fp_line
			(start 0.69215 0.2921)
			(end 0.69215 -0.2921)
			(stroke
				(width 0.1524)
				(type default)
			)
			(layer "B.SilkS")
		)
		(fp_line
			(start -0.51435 -0.2794)
			(end -0.51435 0.2794)
			(stroke
				(width 0.1)
				(type default)
			)
			(layer "B.Fab")
		)
		(fp_line
			(start -0.51435 0.2794)
			(end 0.51435 0.2794)
			(stroke
				(width 0.1)
				(type default)
			)
			(layer "B.Fab")
		)
		(fp_line
			(start 0.51435 -0.2794)
			(end -0.51435 -0.2794)
			(stroke
				(width 0.1)
				(type default)
			)
			(layer "B.Fab")
		)
		(fp_line
			(start 0.51435 0.2794)
			(end 0.51435 -0.2794)
			(stroke
				(width 0.1)
				(type default)
			)
			(layer "B.Fab")
		)
		(pad "1" smd circle
			(at 0.40005 0 180)
			(size 0 0)
			(layers "B.Cu" "B.Mask" "B.Paste")
			(net "P3V3_BIC_USB2AV33")
		)
		(pad "2" smd circle
			(at -0.40005 0 180)
			(size 0 0)
			(layers "B.Cu" "B.Mask" "B.Paste")
			(net "GND")
		)
		(zone
			(layer "B.Cu")
			(hatch none 0.5)
			(connect_pads
				(clearance 0)
			)
			(min_thickness 0.25)
			(keepout
				(tracks not_allowed)
				(vias allowed)
				(pads allowed)
				(copperpour not_allowed)
				(footprints allowed)
			)
			(placement
				(enabled no)
				(sheetname "")
			)
			(fill
				(thermal_gap 0.5)
				(thermal_bridge_width 0.5)
				(island_removal_mode 0)
			)
			(polygon
				(pts
					(xy 232.05821 -216.616534) (xy 231.96677 -216.558368) (xy 231.76738 -216.558368) (xy 231.67721 -216.616534)
					(xy 231.67721 -216.791794) (xy 231.76738 -216.850214) (xy 231.96677 -216.850214) (xy 232.05821 -216.792048)
				)
			)
		)
	)
	(footprint ""
		(layer "B.Cu")
		(at 164.141658 -303.024794)
		(property "Reference" "C3169"
			(at 0 0 0)
			(layer "B.SilkS")
			(hide yes)
			(effects
				(font
					(size 1.27 1.27)
				)
				(justify mirror)
			)
		)
		(property "Value" ""
			(at 0 0 0)
			(layer "B.Fab")
			(effects
				(font
					(size 1.27 1.27)
				)
				(justify mirror)
			)
		)
		(duplicate_pad_numbers_are_jumpers no)
		(fp_line
			(start -0.299974 -0.150114)
			(end -0.299974 0.150114)
			(stroke
				(width 0.1)
				(type default)
			)
			(layer "B.Fab")
		)
		(fp_line
			(start -0.299974 0.150114)
			(end 0.299974 0.150114)
			(stroke
				(width 0.1)
				(type default)
			)
			(layer "B.Fab")
		)
		(fp_line
			(start 0.299974 -0.150114)
			(end -0.299974 -0.150114)
			(stroke
				(width 0.1)
				(type default)
			)
			(layer "B.Fab")
		)
		(fp_line
			(start 0.299974 0.150114)
			(end 0.299974 -0.150114)
			(stroke
				(width 0.1)
				(type default)
			)
			(layer "B.Fab")
		)
		(pad "1" smd rect
			(at 0.2667 0 180)
			(size 0.3048 0.381)
			(layers "B.Cu" "B.Mask" "B.Paste")
			(net "P1V8_VDDA_PEX1")
		)
		(pad "2" smd rect
			(at -0.2667 0 180)
			(size 0.3048 0.381)
			(layers "B.Cu" "B.Mask" "B.Paste")
			(net "GND")
		)
	)
	(footprint ""
		(layer "B.Cu")
		(at 50.624994 -286.399732 90)
		(property "Reference" "C2946"
			(at 0 0 90)
			(layer "B.SilkS")
			(hide yes)
			(effects
				(font
					(size 1.27 1.27)
				)
				(justify mirror)
			)
		)
		(property "Value" ""
			(at 0 0 90)
			(layer "B.Fab")
			(effects
				(font
					(size 1.27 1.27)
				)
				(justify mirror)
			)
		)
		(duplicate_pad_numbers_are_jumpers no)
		(fp_line
			(start 0.299974 -0.150114)
			(end -0.299974 -0.150114)
			(stroke
				(width 0.1)
				(type default)
			)
			(layer "B.Fab")
		)
		(fp_line
			(start -0.299974 -0.150114)
			(end -0.299974 0.150114)
			(stroke
				(width 0.1)
				(type default)
			)
			(layer "B.Fab")
		)
		(fp_line
			(start 0.299974 0.150114)
			(end 0.299974 -0.150114)
			(stroke
				(width 0.1)
				(type default)
			)
			(layer "B.Fab")
		)
		(fp_line
			(start -0.299974 0.150114)
			(end 0.299974 0.150114)
			(stroke
				(width 0.1)
				(type default)
			)
			(layer "B.Fab")
		)
		(pad "1" smd rect
			(at 0.2667 0 270)
			(size 0.3048 0.381)
			(layers "B.Cu" "B.Mask" "B.Paste")
			(net "P1V25_SERDES_VDDPLL_PEX0")
		)
		(pad "2" smd rect
			(at -0.2667 0 270)
			(size 0.3048 0.381)
			(layers "B.Cu" "B.Mask" "B.Paste")
			(net "GND")
		)
	)
	(footprint ""
		(layer "B.Cu")
		(at 305.6001 -111.791496)
		(property "Reference" "C923"
			(at 0 0 0)
			(layer "B.SilkS")
			(hide yes)
			(effects
				(font
					(size 1.27 1.27)
				)
				(justify mirror)
			)
		)
		(property "Value" ""
			(at 0 0 0)
			(layer "B.Fab")
			(effects
				(font
					(size 1.27 1.27)
				)
				(justify mirror)
			)
		)
		(duplicate_pad_numbers_are_jumpers no)
		(fp_line
			(start -0.299974 -0.150114)
			(end -0.299974 0.150114)
			(stroke
				(width 0.1)
				(type default)
			)
			(layer "B.Fab")
		)
		(fp_line
			(start -0.299974 0.150114)
			(end 0.299974 0.150114)
			(stroke
				(width 0.1)
				(type default)
			)
			(layer "B.Fab")
		)
		(fp_line
			(start 0.299974 -0.150114)
			(end -0.299974 -0.150114)
			(stroke
				(width 0.1)
				(type default)
			)
			(layer "B.Fab")
		)
		(fp_line
			(start 0.299974 0.150114)
			(end 0.299974 -0.150114)
			(stroke
				(width 0.1)
				(type default)
			)
			(layer "B.Fab")
		)
		(pad "1" smd rect
			(at 0.2667 0 180)
			(size 0.3048 0.381)
			(layers "B.Cu" "B.Mask" "B.Paste")
			(net "P12V_NIC5")
		)
		(pad "2" smd rect
			(at -0.2667 0 180)
			(size 0.3048 0.381)
			(layers "B.Cu" "B.Mask" "B.Paste")
			(net "GND")
		)
	)
	(footprint ""
		(layer "B.Cu")
		(at 302.299878 -289.724846 180)
		(property "Reference" "C3350"
			(at 0 0 0)
			(layer "B.SilkS")
			(hide yes)
			(effects
				(font
					(size 1.27 1.27)
				)
				(justify mirror)
			)
		)
		(property "Value" ""
			(at 0 0 0)
			(layer "B.Fab")
			(effects
				(font
					(size 1.27 1.27)
				)
				(justify mirror)
			)
		)
		(duplicate_pad_numbers_are_jumpers no)
		(fp_line
			(start 0.299974 0.150114)
			(end 0.299974 -0.150114)
			(stroke
				(width 0.1)
				(type default)
			)
			(layer "B.Fab")
		)
		(fp_line
			(start 0.299974 -0.150114)
			(end -0.299974 -0.150114)
			(stroke
				(width 0.1)
				(type default)
			)
			(layer "B.Fab")
		)
		(fp_line
			(start -0.299974 0.150114)
			(end 0.299974 0.150114)
			(stroke
				(width 0.1)
				(type default)
			)
			(layer "B.Fab")
		)
		(fp_line
			(start -0.299974 -0.150114)
			(end -0.299974 0.150114)
			(stroke
				(width 0.1)
				(type default)
			)
			(layer "B.Fab")
		)
		(pad "1" smd rect
			(at 0.2667 0)
			(size 0.3048 0.381)
			(layers "B.Cu" "B.Mask" "B.Paste")
			(net "P1V8_PEX")
		)
		(pad "2" smd rect
			(at -0.2667 0)
			(size 0.3048 0.381)
			(layers "B.Cu" "B.Mask" "B.Paste")
			(net "GND")
		)
	)
)
